(kicad_pcb
	(version 20241229)
	(generator "pcbnew")
	(generator_version "9.0")
	(general
		(thickness 1.599998)
		(legacy_teardrops no)
	)
	(paper "A4")
	(title_block
		(title "Artix - Datacenter Secure Control Module (DC-SCM)")
		(date "2024-11-06")
		(rev "1.1.3")
		(comment 9 "footprints 319-323 of 544")
	)
	(layers
		(0 "F.Cu" signal)
		(4 "In1.Cu" signal)
		(6 "In2.Cu" signal)
		(8 "In3.Cu" signal)
		(10 "In4.Cu" signal)
		(12 "In5.Cu" signal)
		(14 "In6.Cu" signal)
		(2 "B.Cu" signal)
		(9 "F.Adhes" user "F.Adhesive")
		(11 "B.Adhes" user "B.Adhesive")
		(13 "F.Paste" user)
		(15 "B.Paste" user)
		(5 "F.SilkS" user "F.Silkscreen")
		(7 "B.SilkS" user "B.Silkscreen")
		(1 "F.Mask" user)
		(3 "B.Mask" user)
		(17 "Dwgs.User" user "User.Drawings")
		(19 "Cmts.User" user "User.Comments")
		(21 "Eco1.User" user "User.Eco1")
		(23 "Eco2.User" user "User.Eco2")
		(25 "Edge.Cuts" user)
		(27 "Margin" user)
		(31 "F.CrtYd" user "F.Courtyard")
		(29 "B.CrtYd" user "B.Courtyard")
		(35 "F.Fab" user)
		(33 "B.Fab" user)
	)
	(footprint "antmicro-footprints:C_0402_1005Metric"
		(layer "B.Cu")
		(at 111.325 120.725 180)
		(descr "Capacitor SMD 0402")
		(tags "capacitor SMD 0402")
		(property "Reference" "C118"
			(at -3.623 -0.425 0)
			(layer "B.SilkS")
			(effects
				(font
					(size 0.7 0.7)
					(thickness 0.15)
				)
				(justify left bottom mirror)
			)
		)
		(property "Value" "C_470n_0402"
			(at 0 -1.4 0)
			(layer "B.Fab")
			(effects
				(font
					(size 0.7 0.7)
					(thickness 0.15)
				)
				(justify left bottom mirror)
			)
		)
		(property "Datasheet" "https://product.tdk.com/en/search/capacitor/ceramic/mlcc/info?part_no=C1005X5R1E474M050BB"
			(at 0 0 180)
			(layer "F.Fab")
			(hide yes)
			(effects
				(font
					(size 1.27 1.27)
					(thickness 0.15)
				)
			)
		)
		(property "Description" "SMD Multilayer Ceramic Capacitor, 0.47 µF, 25 V, 0402 [1005 Metric], ± 20%, X5R, C"
			(at 0 0 180)
			(layer "F.Fab")
			(hide yes)
			(effects
				(font
					(size 1.27 1.27)
					(thickness 0.15)
				)
			)
		)
		(property "Author" "Antmicro"
			(at 222.65 241.45 0)
			(layer "B.Fab")
			(hide yes)
			(effects
				(font
					(size 1 1)
					(thickness 0.15)
				)
				(justify mirror)
			)
		)
		(property "Dielectric" ""
			(at 222.65 241.45 0)
			(layer "B.Fab")
			(hide yes)
			(effects
				(font
					(size 1 1)
					(thickness 0.15)
				)
				(justify mirror)
			)
		)
		(property "License" "Apache-2.0"
			(at 222.65 241.45 0)
			(layer "B.Fab")
			(hide yes)
			(effects
				(font
					(size 1 1)
					(thickness 0.15)
				)
				(justify mirror)
			)
		)
		(property "MPN" "C1005X5R1E474M050BB"
			(at 222.65 241.45 0)
			(layer "B.Fab")
			(hide yes)
			(effects
				(font
					(size 1 1)
					(thickness 0.15)
				)
				(justify mirror)
			)
		)
		(property "Manufacturer" "TDK"
			(at 222.65 241.45 0)
			(layer "B.Fab")
			(hide yes)
			(effects
				(font
					(size 1 1)
					(thickness 0.15)
				)
				(justify mirror)
			)
		)
		(property "Val" "470n"
			(at 222.65 241.45 0)
			(layer "B.Fab")
			(hide yes)
			(effects
				(font
					(size 1 1)
					(thickness 0.15)
				)
				(justify mirror)
			)
		)
		(property "Voltage" ""
			(at 222.65 241.45 0)
			(layer "B.Fab")
			(hide yes)
			(effects
				(font
					(size 1 1)
					(thickness 0.15)
				)
				(justify mirror)
			)
		)
		(property "DNP" ""
			(at 0 0 180)
			(unlocked yes)
			(layer "B.Fab")
			(hide yes)
			(effects
				(font
					(size 1 1)
					(thickness 0.15)
				)
				(justify mirror)
			)
		)
		(sheetname "/FPGA banks 13-16/")
		(sheetfile "fpga-banks-13-16.kicad_sch")
		(attr smd)
		(fp_rect
			(start -0.925 0.47)
			(end 0.925 -0.47)
			(stroke
				(width 0.05)
				(type default)
			)
			(fill no)
			(layer "B.CrtYd")
		)
		(fp_line
			(start 0.504 0.25)
			(end 0.504 -0.248)
			(stroke
				(width 0.15)
				(type solid)
			)
			(layer "B.Fab")
		)
		(fp_line
			(start 0.504 -0.248)
			(end -0.494 -0.248)
			(stroke
				(width 0.15)
				(type solid)
			)
			(layer "B.Fab")
		)
		(fp_line
			(start -0.494 0.25)
			(end 0.504 0.25)
			(stroke
				(width 0.15)
				(type solid)
			)
			(layer "B.Fab")
		)
		(fp_line
			(start -0.494 -0.248)
			(end -0.494 0.25)
			(stroke
				(width 0.15)
				(type solid)
			)
			(layer "B.Fab")
		)
		(pad "1" smd roundrect
			(at -0.48 0 180)
			(size 0.59 0.64)
			(layers "B.Cu" "B.Mask" "B.Paste")
			(roundrect_rratio 0.25)
			(net 1 "GND")
			(pintype "passive")
		)
		(pad "2" smd roundrect
			(at 0.48 0 180)
			(size 0.59 0.64)
			(layers "B.Cu" "B.Mask" "B.Paste")
			(roundrect_rratio 0.25)
			(net 2 "VCC3V3")
			(pintype "passive")
		)
	)
	(footprint "antmicro-footprints:C_0402_1005Metric"
		(layer "B.Cu")
		(at 97.775 111.675 180)
		(descr "Capacitor SMD 0402")
		(tags "capacitor SMD 0402")
		(property "Reference" "C124"
			(at -1.425 0.475 0)
			(layer "B.SilkS")
			(effects
				(font
					(size 0.7 0.7)
					(thickness 0.15)
				)
				(justify left bottom mirror)
			)
		)
		(property "Value" "C_470n_0402"
			(at 0 -1.4 0)
			(layer "B.Fab")
			(effects
				(font
					(size 0.7 0.7)
					(thickness 0.15)
				)
				(justify left bottom mirror)
			)
		)
		(property "Datasheet" "https://product.tdk.com/en/search/capacitor/ceramic/mlcc/info?part_no=C1005X5R1E474M050BB"
			(at 0 0 180)
			(layer "F.Fab")
			(hide yes)
			(effects
				(font
					(size 1.27 1.27)
					(thickness 0.15)
				)
			)
		)
		(property "Description" "SMD Multilayer Ceramic Capacitor, 0.47 µF, 25 V, 0402 [1005 Metric], ± 20%, X5R, C"
			(at 0 0 180)
			(layer "F.Fab")
			(hide yes)
			(effects
				(font
					(size 1.27 1.27)
					(thickness 0.15)
				)
			)
		)
		(property "Author" "Antmicro"
			(at 195.55 223.35 0)
			(layer "B.Fab")
			(hide yes)
			(effects
				(font
					(size 1 1)
					(thickness 0.15)
				)
				(justify mirror)
			)
		)
		(property "Dielectric" ""
			(at 195.55 223.35 0)
			(layer "B.Fab")
			(hide yes)
			(effects
				(font
					(size 1 1)
					(thickness 0.15)
				)
				(justify mirror)
			)
		)
		(property "License" "Apache-2.0"
			(at 195.55 223.35 0)
			(layer "B.Fab")
			(hide yes)
			(effects
				(font
					(size 1 1)
					(thickness 0.15)
				)
				(justify mirror)
			)
		)
		(property "MPN" "C1005X5R1E474M050BB"
			(at 195.55 223.35 0)
			(layer "B.Fab")
			(hide yes)
			(effects
				(font
					(size 1 1)
					(thickness 0.15)
				)
				(justify mirror)
			)
		)
		(property "Manufacturer" "TDK"
			(at 195.55 223.35 0)
			(layer "B.Fab")
			(hide yes)
			(effects
				(font
					(size 1 1)
					(thickness 0.15)
				)
				(justify mirror)
			)
		)
		(property "Val" "470n"
			(at 195.55 223.35 0)
			(layer "B.Fab")
			(hide yes)
			(effects
				(font
					(size 1 1)
					(thickness 0.15)
				)
				(justify mirror)
			)
		)
		(property "Voltage" ""
			(at 195.55 223.35 0)
			(layer "B.Fab")
			(hide yes)
			(effects
				(font
					(size 1 1)
					(thickness 0.15)
				)
				(justify mirror)
			)
		)
		(property "DNP" ""
			(at 0 0 180)
			(unlocked yes)
			(layer "B.Fab")
			(hide yes)
			(effects
				(font
					(size 1 1)
					(thickness 0.15)
				)
				(justify mirror)
			)
		)
		(sheetname "/FPGA banks 13-16/")
		(sheetfile "fpga-banks-13-16.kicad_sch")
		(attr smd)
		(fp_rect
			(start -0.925 0.47)
			(end 0.925 -0.47)
			(stroke
				(width 0.05)
				(type default)
			)
			(fill no)
			(layer "B.CrtYd")
		)
		(fp_line
			(start 0.504 0.25)
			(end 0.504 -0.248)
			(stroke
				(width 0.15)
				(type solid)
			)
			(layer "B.Fab")
		)
		(fp_line
			(start 0.504 -0.248)
			(end -0.494 -0.248)
			(stroke
				(width 0.15)
				(type solid)
			)
			(layer "B.Fab")
		)
		(fp_line
			(start -0.494 0.25)
			(end 0.504 0.25)
			(stroke
				(width 0.15)
				(type solid)
			)
			(layer "B.Fab")
		)
		(fp_line
			(start -0.494 -0.248)
			(end -0.494 0.25)
			(stroke
				(width 0.15)
				(type solid)
			)
			(layer "B.Fab")
		)
		(pad "1" smd roundrect
			(at -0.48 0 180)
			(size 0.59 0.64)
			(layers "B.Cu" "B.Mask" "B.Paste")
			(roundrect_rratio 0.25)
			(net 1 "GND")
			(pintype "passive")
		)
		(pad "2" smd roundrect
			(at 0.48 0 180)
			(size 0.59 0.64)
			(layers "B.Cu" "B.Mask" "B.Paste")
			(roundrect_rratio 0.25)
			(net 2 "VCC3V3")
			(pintype "passive")
		)
	)
	(footprint "antmicro-footprints:C_0402_1005Metric"
		(layer "B.Cu")
		(at 107.775 125.525 180)
		(descr "Capacitor SMD 0402")
		(tags "capacitor SMD 0402")
		(property "Reference" "C113"
			(at -1.625 -4.375 0)
			(layer "B.SilkS")
			(effects
				(font
					(size 0.7 0.7)
					(thickness 0.15)
				)
				(justify left bottom mirror)
			)
		)
		(property "Value" "C_470n_0402"
			(at 0 -1.4 0)
			(layer "B.Fab")
			(effects
				(font
					(size 0.7 0.7)
					(thickness 0.15)
				)
				(justify left bottom mirror)
			)
		)
		(property "Datasheet" "https://product.tdk.com/en/search/capacitor/ceramic/mlcc/info?part_no=C1005X5R1E474M050BB"
			(at 0 0 180)
			(layer "F.Fab")
			(hide yes)
			(effects
				(font
					(size 1.27 1.27)
					(thickness 0.15)
				)
			)
		)
		(property "Description" "SMD Multilayer Ceramic Capacitor, 0.47 µF, 25 V, 0402 [1005 Metric], ± 20%, X5R, C"
			(at 0 0 180)
			(layer "F.Fab")
			(hide yes)
			(effects
				(font
					(size 1.27 1.27)
					(thickness 0.15)
				)
			)
		)
		(property "Author" "Antmicro"
			(at 215.55 251.05 0)
			(layer "B.Fab")
			(hide yes)
			(effects
				(font
					(size 1 1)
					(thickness 0.15)
				)
				(justify mirror)
			)
		)
		(property "Dielectric" ""
			(at 215.55 251.05 0)
			(layer "B.Fab")
			(hide yes)
			(effects
				(font
					(size 1 1)
					(thickness 0.15)
				)
				(justify mirror)
			)
		)
		(property "License" "Apache-2.0"
			(at 215.55 251.05 0)
			(layer "B.Fab")
			(hide yes)
			(effects
				(font
					(size 1 1)
					(thickness 0.15)
				)
				(justify mirror)
			)
		)
		(property "MPN" "C1005X5R1E474M050BB"
			(at 215.55 251.05 0)
			(layer "B.Fab")
			(hide yes)
			(effects
				(font
					(size 1 1)
					(thickness 0.15)
				)
				(justify mirror)
			)
		)
		(property "Manufacturer" "TDK"
			(at 215.55 251.05 0)
			(layer "B.Fab")
			(hide yes)
			(effects
				(font
					(size 1 1)
					(thickness 0.15)
				)
				(justify mirror)
			)
		)
		(property "Val" "470n"
			(at 215.55 251.05 0)
			(layer "B.Fab")
			(hide yes)
			(effects
				(font
					(size 1 1)
					(thickness 0.15)
				)
				(justify mirror)
			)
		)
		(property "Voltage" ""
			(at 215.55 251.05 0)
			(layer "B.Fab")
			(hide yes)
			(effects
				(font
					(size 1 1)
					(thickness 0.15)
				)
				(justify mirror)
			)
		)
		(sheetname "/FPGA banks 13-16/")
		(sheetfile "fpga-banks-13-16.kicad_sch")
		(attr smd)
		(fp_rect
			(start -0.925 0.47)
			(end 0.925 -0.47)
			(stroke
				(width 0.05)
				(type default)
			)
			(fill no)
			(layer "B.CrtYd")
		)
		(fp_line
			(start 0.504 0.25)
			(end 0.504 -0.248)
			(stroke
				(width 0.15)
				(type solid)
			)
			(layer "B.Fab")
		)
		(fp_line
			(start 0.504 -0.248)
			(end -0.494 -0.248)
			(stroke
				(width 0.15)
				(type solid)
			)
			(layer "B.Fab")
		)
		(fp_line
			(start -0.494 0.25)
			(end 0.504 0.25)
			(stroke
				(width 0.15)
				(type solid)
			)
			(layer "B.Fab")
		)
		(fp_line
			(start -0.494 -0.248)
			(end -0.494 0.25)
			(stroke
				(width 0.15)
				(type solid)
			)
			(layer "B.Fab")
		)
		(pad "1" smd roundrect
			(at -0.48 0 180)
			(size 0.59 0.64)
			(layers "B.Cu" "B.Mask" "B.Paste")
			(roundrect_rratio 0.25)
			(net 1 "GND")
			(pintype "passive")
		)
		(pad "2" smd roundrect
			(at 0.48 0 180)
			(size 0.59 0.64)
			(layers "B.Cu" "B.Mask" "B.Paste")
			(roundrect_rratio 0.25)
			(net 2 "VCC3V3")
			(pintype "passive")
		)
	)
	(footprint "antmicro-footprints:C_0402_1005Metric"
		(layer "B.Cu")
		(at 107.8 126.6 180)
		(descr "Capacitor SMD 0402")
		(tags "capacitor SMD 0402")
		(property "Reference" "C125"
			(at -1.6 -4.4 0)
			(layer "B.SilkS")
			(effects
				(font
					(size 0.7 0.7)
					(thickness 0.15)
				)
				(justify left bottom mirror)
			)
		)
		(property "Value" "C_470n_0402"
			(at 0 -1.4 0)
			(layer "B.Fab")
			(effects
				(font
					(size 0.7 0.7)
					(thickness 0.15)
				)
				(justify left bottom mirror)
			)
		)
		(property "Datasheet" "https://product.tdk.com/en/search/capacitor/ceramic/mlcc/info?part_no=C1005X5R1E474M050BB"
			(at 0 0 180)
			(layer "F.Fab")
			(hide yes)
			(effects
				(font
					(size 1.27 1.27)
					(thickness 0.15)
				)
			)
		)
		(property "Description" "SMD Multilayer Ceramic Capacitor, 0.47 µF, 25 V, 0402 [1005 Metric], ± 20%, X5R, C"
			(at 0 0 180)
			(layer "F.Fab")
			(hide yes)
			(effects
				(font
					(size 1.27 1.27)
					(thickness 0.15)
				)
			)
		)
		(property "Author" "Antmicro"
			(at 215.6 253.2 0)
			(layer "B.Fab")
			(hide yes)
			(effects
				(font
					(size 1 1)
					(thickness 0.15)
				)
				(justify mirror)
			)
		)
		(property "Dielectric" ""
			(at 215.6 253.2 0)
			(layer "B.Fab")
			(hide yes)
			(effects
				(font
					(size 1 1)
					(thickness 0.15)
				)
				(justify mirror)
			)
		)
		(property "License" "Apache-2.0"
			(at 215.6 253.2 0)
			(layer "B.Fab")
			(hide yes)
			(effects
				(font
					(size 1 1)
					(thickness 0.15)
				)
				(justify mirror)
			)
		)
		(property "MPN" "C1005X5R1E474M050BB"
			(at 215.6 253.2 0)
			(layer "B.Fab")
			(hide yes)
			(effects
				(font
					(size 1 1)
					(thickness 0.15)
				)
				(justify mirror)
			)
		)
		(property "Manufacturer" "TDK"
			(at 215.6 253.2 0)
			(layer "B.Fab")
			(hide yes)
			(effects
				(font
					(size 1 1)
					(thickness 0.15)
				)
				(justify mirror)
			)
		)
		(property "Val" "470n"
			(at 215.6 253.2 0)
			(layer "B.Fab")
			(hide yes)
			(effects
				(font
					(size 1 1)
					(thickness 0.15)
				)
				(justify mirror)
			)
		)
		(property "Voltage" ""
			(at 215.6 253.2 0)
			(layer "B.Fab")
			(hide yes)
			(effects
				(font
					(size 1 1)
					(thickness 0.15)
				)
				(justify mirror)
			)
		)
		(sheetname "/FPGA banks 13-16/")
		(sheetfile "fpga-banks-13-16.kicad_sch")
		(attr smd)
		(fp_rect
			(start -0.925 0.47)
			(end 0.925 -0.47)
			(stroke
				(width 0.05)
				(type default)
			)
			(fill no)
			(layer "B.CrtYd")
		)
		(fp_line
			(start 0.504 0.25)
			(end 0.504 -0.248)
			(stroke
				(width 0.15)
				(type solid)
			)
			(layer "B.Fab")
		)
		(fp_line
			(start 0.504 -0.248)
			(end -0.494 -0.248)
			(stroke
				(width 0.15)
				(type solid)
			)
			(layer "B.Fab")
		)
		(fp_line
			(start -0.494 0.25)
			(end 0.504 0.25)
			(stroke
				(width 0.15)
				(type solid)
			)
			(layer "B.Fab")
		)
		(fp_line
			(start -0.494 -0.248)
			(end -0.494 0.25)
			(stroke
				(width 0.15)
				(type solid)
			)
			(layer "B.Fab")
		)
		(pad "1" smd roundrect
			(at -0.48 0 180)
			(size 0.59 0.64)
			(layers "B.Cu" "B.Mask" "B.Paste")
			(roundrect_rratio 0.25)
			(net 1 "GND")
			(pintype "passive")
		)
		(pad "2" smd roundrect
			(at 0.48 0 180)
			(size 0.59 0.64)
			(layers "B.Cu" "B.Mask" "B.Paste")
			(roundrect_rratio 0.25)
			(net 2 "VCC3V3")
			(pintype "passive")
		)
	)
	(footprint "antmicro-footprints:C_0402_1005Metric"
		(layer "B.Cu")
		(at 105.5 126.7)
		(descr "Capacitor SMD 0402")
		(tags "capacitor SMD 0402")
		(property "Reference" "C131"
			(at -1.8 4.3 0)
			(layer "B.SilkS")
			(effects
				(font
					(size 0.7 0.7)
					(thickness 0.15)
				)
				(justify right bottom mirror)
			)
		)
		(property "Value" "C_470n_0402"
			(at 0 -1.4 0)
			(layer "B.Fab")
			(effects
				(font
					(size 0.7 0.7)
					(thickness 0.15)
				)
				(justify right bottom mirror)
			)
		)
		(property "Datasheet" "https://product.tdk.com/en/search/capacitor/ceramic/mlcc/info?part_no=C1005X5R1E474M050BB"
			(at 0 0 0)
			(layer "F.Fab")
			(hide yes)
			(effects
				(font
					(size 1.27 1.27)
					(thickness 0.15)
				)
			)
		)
		(property "Description" "SMD Multilayer Ceramic Capacitor, 0.47 µF, 25 V, 0402 [1005 Metric], ± 20%, X5R, C"
			(at 0 0 0)
			(layer "F.Fab")
			(hide yes)
			(effects
				(font
					(size 1.27 1.27)
					(thickness 0.15)
				)
			)
		)
		(property "Author" "Antmicro"
			(at 0 0 0)
			(layer "B.Fab")
			(hide yes)
			(effects
				(font
					(size 1 1)
					(thickness 0.15)
				)
				(justify mirror)
			)
		)
		(property "Dielectric" ""
			(at 0 0 0)
			(layer "B.Fab")
			(hide yes)
			(effects
				(font
					(size 1 1)
					(thickness 0.15)
				)
				(justify mirror)
			)
		)
		(property "License" "Apache-2.0"
			(at 0 0 0)
			(layer "B.Fab")
			(hide yes)
			(effects
				(font
					(size 1 1)
					(thickness 0.15)
				)
				(justify mirror)
			)
		)
		(property "MPN" "C1005X5R1E474M050BB"
			(at 0 0 0)
			(layer "B.Fab")
			(hide yes)
			(effects
				(font
					(size 1 1)
					(thickness 0.15)
				)
				(justify mirror)
			)
		)
		(property "Manufacturer" "TDK"
			(at 0 0 0)
			(layer "B.Fab")
			(hide yes)
			(effects
				(font
					(size 1 1)
					(thickness 0.15)
				)
				(justify mirror)
			)
		)
		(property "Val" "470n"
			(at 0 0 0)
			(layer "B.Fab")
			(hide yes)
			(effects
				(font
					(size 1 1)
					(thickness 0.15)
				)
				(justify mirror)
			)
		)
		(property "Voltage" ""
			(at 0 0 0)
			(layer "B.Fab")
			(hide yes)
			(effects
				(font
					(size 1 1)
					(thickness 0.15)
				)
				(justify mirror)
			)
		)
		(sheetname "/FPGA banks 13-16/")
		(sheetfile "fpga-banks-13-16.kicad_sch")
		(attr smd)
		(fp_rect
			(start -0.925 0.47)
			(end 0.925 -0.47)
			(stroke
				(width 0.05)
				(type default)
			)
			(fill no)
			(layer "B.CrtYd")
		)
		(fp_line
			(start -0.494 -0.248)
			(end -0.494 0.25)
			(stroke
				(width 0.15)
				(type solid)
			)
			(layer "B.Fab")
		)
		(fp_line
			(start -0.494 0.25)
			(end 0.504 0.25)
			(stroke
				(width 0.15)
				(type solid)
			)
			(layer "B.Fab")
		)
		(fp_line
			(start 0.504 -0.248)
			(end -0.494 -0.248)
			(stroke
				(width 0.15)
				(type solid)
			)
			(layer "B.Fab")
		)
		(fp_line
			(start 0.504 0.25)
			(end 0.504 -0.248)
			(stroke
				(width 0.15)
				(type solid)
			)
			(layer "B.Fab")
		)
		(pad "1" smd roundrect
			(at -0.48 0)
			(size 0.59 0.64)
			(layers "B.Cu" "B.Mask" "B.Paste")
			(roundrect_rratio 0.25)
			(net 1 "GND")
			(pintype "passive")
		)
		(pad "2" smd roundrect
			(at 0.48 0)
			(size 0.59 0.64)
			(layers "B.Cu" "B.Mask" "B.Paste")
			(roundrect_rratio 0.25)
			(net 2 "VCC3V3")
			(pintype "passive")
		)
	)
)
